(kicad_pcb
	(version 20260206)
	(generator "pcbnew")
	(generator_version "10.0")
	(general
		(thickness 1.6)
		(legacy_teardrops no)
	)
	(paper "A4")
	(title_block
		(title "03242023_DA0F0TMBIJ0_F0T_Motherboard_J_brd_V01_OCP.brd")
		(comment 1 "Grand Teton / footprints 2610-2615 of 6105")
	)
	(layers
		(0 "F.Cu" signal "TOP")
		(4 "In1.Cu" signal "GND")
		(6 "In2.Cu" signal "IN1")
		(8 "In3.Cu" signal "GND1")
		(10 "In4.Cu" signal "IN2")
		(12 "In5.Cu" signal "GND2")
		(14 "In6.Cu" signal "IN3")
		(16 "In7.Cu" signal "GND3")
		(18 "In8.Cu" signal "VCC")
		(20 "In9.Cu" signal "VCC1")
		(22 "In10.Cu" signal "GND4")
		(24 "In11.Cu" signal "IN4")
		(26 "In12.Cu" signal "GND5")
		(28 "In13.Cu" signal "IN5")
		(30 "In14.Cu" signal "GND6")
		(32 "In15.Cu" signal "IN6")
		(34 "In16.Cu" signal "GND7")
		(2 "B.Cu" signal "BOTTOM")
		(9 "F.Adhes" user "F.Adhesive")
		(11 "B.Adhes" user "B.Adhesive")
		(13 "F.Paste" user "Package Geometry/Pastemask Top")
		(15 "B.Paste" user "Package Geometry/Pastemask Bottom")
		(5 "F.SilkS" user "Ref Des/Silkscreen Top")
		(7 "B.SilkS" user "Ref Des/Silkscreen Bottom")
		(1 "F.Mask" user "Board Geometry/Soldermask Top")
		(3 "B.Mask" user "Board Geometry/Soldermask Bottom")
		(17 "Dwgs.User" user "User.Drawings")
		(19 "Cmts.User" user "User.Comments")
		(21 "Eco1.User" user "User.Eco1")
		(23 "Eco2.User" user "User.Eco2")
		(25 "Edge.Cuts" user "Board Geometry/Outline")
		(27 "Margin" user)
		(31 "F.CrtYd" user "Package Geometry/Place Bound Top")
		(29 "B.CrtYd" user "Package Geometry/Place Bound Bottom")
		(35 "F.Fab" user "Ref Des/Assembly Top")
		(33 "B.Fab" user "Ref Des/Assembly Bottom")
	)
	(footprint ""
		(layer "F.Cu")
		(at 226.733608 -406.855422)
		(property "Reference" "PR3993"
			(at 0 0 0)
			(layer "F.SilkS")
			(hide yes)
			(effects
				(font
					(size 1.27 1.27)
				)
			)
		)
		(property "Value" ""
			(at 0 0 0)
			(layer "F.Fab")
			(effects
				(font
					(size 1.27 1.27)
				)
			)
		)
		(duplicate_pad_numbers_are_jumpers no)
		(fp_line
			(start -0.7874 -0.4064)
			(end 0.7874 -0.4064)
			(stroke
				(width 0.1524)
				(type default)
			)
			(layer "F.SilkS")
		)
		(fp_line
			(start -0.7874 0.4064)
			(end -0.7874 -0.4064)
			(stroke
				(width 0.1524)
				(type default)
			)
			(layer "F.SilkS")
		)
		(fp_line
			(start 0.7874 -0.4064)
			(end 0.7874 0.4064)
			(stroke
				(width 0.1524)
				(type default)
			)
			(layer "F.SilkS")
		)
		(fp_line
			(start 0.7874 0.4064)
			(end -0.7874 0.4064)
			(stroke
				(width 0.1524)
				(type default)
			)
			(layer "F.SilkS")
		)
		(fp_line
			(start -0.67945 -0.305054)
			(end -0.12065 -0.305054)
			(stroke
				(width 0.1)
				(type default)
			)
			(layer "F.Fab")
		)
		(fp_line
			(start -0.67945 0.3048)
			(end -0.67945 -0.305054)
			(stroke
				(width 0.1)
				(type default)
			)
			(layer "F.Fab")
		)
		(fp_line
			(start -0.12065 -0.305054)
			(end -0.12065 -0.2794)
			(stroke
				(width 0.1)
				(type default)
			)
			(layer "F.Fab")
		)
		(fp_line
			(start -0.12065 -0.2794)
			(end 0.12065 -0.2794)
			(stroke
				(width 0.1)
				(type default)
			)
			(layer "F.Fab")
		)
		(fp_line
			(start -0.12065 0.2794)
			(end -0.12065 0.3048)
			(stroke
				(width 0.1)
				(type default)
			)
			(layer "F.Fab")
		)
		(fp_line
			(start -0.12065 0.3048)
			(end -0.67945 0.3048)
			(stroke
				(width 0.1)
				(type default)
			)
			(layer "F.Fab")
		)
		(fp_line
			(start 0.120396 0.2794)
			(end -0.12065 0.2794)
			(stroke
				(width 0.1)
				(type default)
			)
			(layer "F.Fab")
		)
		(fp_line
			(start 0.120396 0.3048)
			(end 0.120396 0.2794)
			(stroke
				(width 0.1)
				(type default)
			)
			(layer "F.Fab")
		)
		(fp_line
			(start 0.12065 -0.3048)
			(end 0.67945 -0.3048)
			(stroke
				(width 0.1)
				(type default)
			)
			(layer "F.Fab")
		)
		(fp_line
			(start 0.12065 -0.2794)
			(end 0.12065 -0.3048)
			(stroke
				(width 0.1)
				(type default)
			)
			(layer "F.Fab")
		)
		(fp_line
			(start 0.67945 -0.3048)
			(end 0.67945 0.3048)
			(stroke
				(width 0.1)
				(type default)
			)
			(layer "F.Fab")
		)
		(fp_line
			(start 0.67945 0.3048)
			(end 0.120396 0.3048)
			(stroke
				(width 0.1)
				(type default)
			)
			(layer "F.Fab")
		)
		(pad "1" smd circle
			(at -0.40005 0)
			(size 0 0)
			(layers "F.Cu" "F.Mask" "F.Paste")
			(net "HSC_FLT_TYPE_3")
		)
		(pad "2" smd circle
			(at 0.40005 0)
			(size 0 0)
			(layers "F.Cu" "F.Mask" "F.Paste")
			(net "HSC_FLT_TYPE")
		)
	)
	(footprint ""
		(layer "F.Cu")
		(at 104.22001 -353.14255)
		(property "Reference" "PR317"
			(at 0 0 0)
			(layer "F.SilkS")
			(hide yes)
			(effects
				(font
					(size 1.27 1.27)
				)
			)
		)
		(property "Value" ""
			(at 0 0 0)
			(layer "F.Fab")
			(effects
				(font
					(size 1.27 1.27)
				)
			)
		)
		(duplicate_pad_numbers_are_jumpers no)
		(fp_line
			(start -0.7874 -0.4064)
			(end 0.7874 -0.4064)
			(stroke
				(width 0.1524)
				(type default)
			)
			(layer "F.SilkS")
		)
		(fp_line
			(start -0.7874 0.4064)
			(end -0.7874 -0.4064)
			(stroke
				(width 0.1524)
				(type default)
			)
			(layer "F.SilkS")
		)
		(fp_line
			(start 0.7874 -0.4064)
			(end 0.7874 0.4064)
			(stroke
				(width 0.1524)
				(type default)
			)
			(layer "F.SilkS")
		)
		(fp_line
			(start 0.7874 0.4064)
			(end -0.7874 0.4064)
			(stroke
				(width 0.1524)
				(type default)
			)
			(layer "F.SilkS")
		)
		(fp_line
			(start -0.67945 -0.305054)
			(end -0.12065 -0.305054)
			(stroke
				(width 0.1)
				(type default)
			)
			(layer "F.Fab")
		)
		(fp_line
			(start -0.67945 0.3048)
			(end -0.67945 -0.305054)
			(stroke
				(width 0.1)
				(type default)
			)
			(layer "F.Fab")
		)
		(fp_line
			(start -0.12065 -0.305054)
			(end -0.12065 -0.2794)
			(stroke
				(width 0.1)
				(type default)
			)
			(layer "F.Fab")
		)
		(fp_line
			(start -0.12065 -0.2794)
			(end 0.12065 -0.2794)
			(stroke
				(width 0.1)
				(type default)
			)
			(layer "F.Fab")
		)
		(fp_line
			(start -0.12065 0.2794)
			(end -0.12065 0.3048)
			(stroke
				(width 0.1)
				(type default)
			)
			(layer "F.Fab")
		)
		(fp_line
			(start -0.12065 0.3048)
			(end -0.67945 0.3048)
			(stroke
				(width 0.1)
				(type default)
			)
			(layer "F.Fab")
		)
		(fp_line
			(start 0.120396 0.2794)
			(end -0.12065 0.2794)
			(stroke
				(width 0.1)
				(type default)
			)
			(layer "F.Fab")
		)
		(fp_line
			(start 0.120396 0.3048)
			(end 0.120396 0.2794)
			(stroke
				(width 0.1)
				(type default)
			)
			(layer "F.Fab")
		)
		(fp_line
			(start 0.12065 -0.3048)
			(end 0.67945 -0.3048)
			(stroke
				(width 0.1)
				(type default)
			)
			(layer "F.Fab")
		)
		(fp_line
			(start 0.12065 -0.2794)
			(end 0.12065 -0.3048)
			(stroke
				(width 0.1)
				(type default)
			)
			(layer "F.Fab")
		)
		(fp_line
			(start 0.67945 -0.3048)
			(end 0.67945 0.3048)
			(stroke
				(width 0.1)
				(type default)
			)
			(layer "F.Fab")
		)
		(fp_line
			(start 0.67945 0.3048)
			(end 0.120396 0.3048)
			(stroke
				(width 0.1)
				(type default)
			)
			(layer "F.Fab")
		)
		(pad "1" smd circle
			(at -0.40005 0)
			(size 0 0)
			(layers "F.Cu" "F.Mask" "F.Paste")
			(net "SH_PVCCIN_CPU1")
		)
		(pad "2" smd circle
			(at 0.40005 0)
			(size 0 0)
			(layers "F.Cu" "F.Mask" "F.Paste")
			(net "SH_PVCCIN_CPU1_R")
		)
	)
	(footprint ""
		(layer "F.Cu")
		(at 424.204892 -380.329948 180)
		(property "Reference" "C1772"
			(at 0 0 180)
			(layer "F.SilkS")
			(hide yes)
			(effects
				(font
					(size 1.27 1.27)
				)
			)
		)
		(property "Value" ""
			(at 0 0 180)
			(layer "F.Fab")
			(effects
				(font
					(size 1.27 1.27)
				)
			)
		)
		(duplicate_pad_numbers_are_jumpers no)
		(fp_line
			(start 0.7874 0.4064)
			(end -0.7874 0.4064)
			(stroke
				(width 0.1524)
				(type default)
			)
			(layer "F.SilkS")
		)
		(fp_line
			(start 0.7874 -0.4064)
			(end 0.7874 0.4064)
			(stroke
				(width 0.1524)
				(type default)
			)
			(layer "F.SilkS")
		)
		(fp_line
			(start -0.7874 0.4064)
			(end -0.7874 -0.4064)
			(stroke
				(width 0.1524)
				(type default)
			)
			(layer "F.SilkS")
		)
		(fp_line
			(start -0.7874 -0.4064)
			(end 0.7874 -0.4064)
			(stroke
				(width 0.1524)
				(type default)
			)
			(layer "F.SilkS")
		)
		(fp_line
			(start 0.67945 0.3048)
			(end 0.120396 0.3048)
			(stroke
				(width 0.1)
				(type default)
			)
			(layer "F.Fab")
		)
		(fp_line
			(start 0.67945 -0.3048)
			(end 0.67945 0.3048)
			(stroke
				(width 0.1)
				(type default)
			)
			(layer "F.Fab")
		)
		(fp_line
			(start 0.12065 -0.2794)
			(end 0.12065 -0.3048)
			(stroke
				(width 0.1)
				(type default)
			)
			(layer "F.Fab")
		)
		(fp_line
			(start 0.12065 -0.3048)
			(end 0.67945 -0.3048)
			(stroke
				(width 0.1)
				(type default)
			)
			(layer "F.Fab")
		)
		(fp_line
			(start 0.120396 0.3048)
			(end 0.120396 0.2794)
			(stroke
				(width 0.1)
				(type default)
			)
			(layer "F.Fab")
		)
		(fp_line
			(start 0.120396 0.2794)
			(end -0.12065 0.2794)
			(stroke
				(width 0.1)
				(type default)
			)
			(layer "F.Fab")
		)
		(fp_line
			(start -0.12065 0.3048)
			(end -0.67945 0.3048)
			(stroke
				(width 0.1)
				(type default)
			)
			(layer "F.Fab")
		)
		(fp_line
			(start -0.12065 0.2794)
			(end -0.12065 0.3048)
			(stroke
				(width 0.1)
				(type default)
			)
			(layer "F.Fab")
		)
		(fp_line
			(start -0.12065 -0.2794)
			(end 0.12065 -0.2794)
			(stroke
				(width 0.1)
				(type default)
			)
			(layer "F.Fab")
		)
		(fp_line
			(start -0.12065 -0.305054)
			(end -0.12065 -0.2794)
			(stroke
				(width 0.1)
				(type default)
			)
			(layer "F.Fab")
		)
		(fp_line
			(start -0.67945 0.3048)
			(end -0.67945 -0.305054)
			(stroke
				(width 0.1)
				(type default)
			)
			(layer "F.Fab")
		)
		(fp_line
			(start -0.67945 -0.305054)
			(end -0.12065 -0.305054)
			(stroke
				(width 0.1)
				(type default)
			)
			(layer "F.Fab")
		)
		(pad "1" smd circle
			(at -0.40005 0 180)
			(size 0 0)
			(layers "F.Cu" "F.Mask" "F.Paste")
			(net "RST_BMC_FROM_SWB_ISO_N")
		)
		(pad "2" smd circle
			(at 0.40005 0 180)
			(size 0 0)
			(layers "F.Cu" "F.Mask" "F.Paste")
			(net "GND")
		)
	)
	(footprint ""
		(layer "F.Cu")
		(at 115.060222 -19.30019)
		(property "Reference" "C2274"
			(at 0 0 0)
			(layer "F.SilkS")
			(hide yes)
			(effects
				(font
					(size 1.27 1.27)
				)
			)
		)
		(property "Value" ""
			(at 0 0 0)
			(layer "F.Fab")
			(effects
				(font
					(size 1.27 1.27)
				)
			)
		)
		(duplicate_pad_numbers_are_jumpers no)
		(fp_line
			(start -0.7874 -0.4064)
			(end 0.7874 -0.4064)
			(stroke
				(width 0.1524)
				(type default)
			)
			(layer "F.SilkS")
		)
		(fp_line
			(start -0.7874 0.4064)
			(end -0.7874 -0.4064)
			(stroke
				(width 0.1524)
				(type default)
			)
			(layer "F.SilkS")
		)
		(fp_line
			(start 0.7874 -0.4064)
			(end 0.7874 0.4064)
			(stroke
				(width 0.1524)
				(type default)
			)
			(layer "F.SilkS")
		)
		(fp_line
			(start 0.7874 0.4064)
			(end -0.7874 0.4064)
			(stroke
				(width 0.1524)
				(type default)
			)
			(layer "F.SilkS")
		)
		(fp_line
			(start -0.67945 -0.305054)
			(end -0.12065 -0.305054)
			(stroke
				(width 0.1)
				(type default)
			)
			(layer "F.Fab")
		)
		(fp_line
			(start -0.67945 0.3048)
			(end -0.67945 -0.305054)
			(stroke
				(width 0.1)
				(type default)
			)
			(layer "F.Fab")
		)
		(fp_line
			(start -0.12065 -0.305054)
			(end -0.12065 -0.2794)
			(stroke
				(width 0.1)
				(type default)
			)
			(layer "F.Fab")
		)
		(fp_line
			(start -0.12065 -0.2794)
			(end 0.12065 -0.2794)
			(stroke
				(width 0.1)
				(type default)
			)
			(layer "F.Fab")
		)
		(fp_line
			(start -0.12065 0.2794)
			(end -0.12065 0.3048)
			(stroke
				(width 0.1)
				(type default)
			)
			(layer "F.Fab")
		)
		(fp_line
			(start -0.12065 0.3048)
			(end -0.67945 0.3048)
			(stroke
				(width 0.1)
				(type default)
			)
			(layer "F.Fab")
		)
		(fp_line
			(start 0.120396 0.2794)
			(end -0.12065 0.2794)
			(stroke
				(width 0.1)
				(type default)
			)
			(layer "F.Fab")
		)
		(fp_line
			(start 0.120396 0.3048)
			(end 0.120396 0.2794)
			(stroke
				(width 0.1)
				(type default)
			)
			(layer "F.Fab")
		)
		(fp_line
			(start 0.12065 -0.3048)
			(end 0.67945 -0.3048)
			(stroke
				(width 0.1)
				(type default)
			)
			(layer "F.Fab")
		)
		(fp_line
			(start 0.12065 -0.2794)
			(end 0.12065 -0.3048)
			(stroke
				(width 0.1)
				(type default)
			)
			(layer "F.Fab")
		)
		(fp_line
			(start 0.67945 -0.3048)
			(end 0.67945 0.3048)
			(stroke
				(width 0.1)
				(type default)
			)
			(layer "F.Fab")
		)
		(fp_line
			(start 0.67945 0.3048)
			(end 0.120396 0.3048)
			(stroke
				(width 0.1)
				(type default)
			)
			(layer "F.Fab")
		)
		(pad "1" smd circle
			(at -0.40005 0)
			(size 0 0)
			(layers "F.Cu" "F.Mask" "F.Paste")
			(net "P3V3_AUX")
		)
		(pad "2" smd circle
			(at 0.40005 0)
			(size 0 0)
			(layers "F.Cu" "F.Mask" "F.Paste")
			(net "GND")
		)
	)
	(footprint ""
		(layer "F.Cu")
		(at 113.494312 -131.440682 180)
		(property "Reference" "R2968"
			(at 0 0 180)
			(layer "F.SilkS")
			(hide yes)
			(effects
				(font
					(size 1.27 1.27)
				)
			)
		)
		(property "Value" ""
			(at 0 0 180)
			(layer "F.Fab")
			(effects
				(font
					(size 1.27 1.27)
				)
			)
		)
		(duplicate_pad_numbers_are_jumpers no)
		(fp_line
			(start 0.7874 0.4064)
			(end -0.7874 0.4064)
			(stroke
				(width 0.1524)
				(type default)
			)
			(layer "F.SilkS")
		)
		(fp_line
			(start 0.7874 -0.4064)
			(end 0.7874 0.4064)
			(stroke
				(width 0.1524)
				(type default)
			)
			(layer "F.SilkS")
		)
		(fp_line
			(start -0.7874 0.4064)
			(end -0.7874 -0.4064)
			(stroke
				(width 0.1524)
				(type default)
			)
			(layer "F.SilkS")
		)
		(fp_line
			(start -0.7874 -0.4064)
			(end 0.7874 -0.4064)
			(stroke
				(width 0.1524)
				(type default)
			)
			(layer "F.SilkS")
		)
		(fp_line
			(start 0.67945 0.3048)
			(end 0.120396 0.3048)
			(stroke
				(width 0.1)
				(type default)
			)
			(layer "F.Fab")
		)
		(fp_line
			(start 0.67945 -0.3048)
			(end 0.67945 0.3048)
			(stroke
				(width 0.1)
				(type default)
			)
			(layer "F.Fab")
		)
		(fp_line
			(start 0.12065 -0.2794)
			(end 0.12065 -0.3048)
			(stroke
				(width 0.1)
				(type default)
			)
			(layer "F.Fab")
		)
		(fp_line
			(start 0.12065 -0.3048)
			(end 0.67945 -0.3048)
			(stroke
				(width 0.1)
				(type default)
			)
			(layer "F.Fab")
		)
		(fp_line
			(start 0.120396 0.3048)
			(end 0.120396 0.2794)
			(stroke
				(width 0.1)
				(type default)
			)
			(layer "F.Fab")
		)
		(fp_line
			(start 0.120396 0.2794)
			(end -0.12065 0.2794)
			(stroke
				(width 0.1)
				(type default)
			)
			(layer "F.Fab")
		)
		(fp_line
			(start -0.12065 0.3048)
			(end -0.67945 0.3048)
			(stroke
				(width 0.1)
				(type default)
			)
			(layer "F.Fab")
		)
		(fp_line
			(start -0.12065 0.2794)
			(end -0.12065 0.3048)
			(stroke
				(width 0.1)
				(type default)
			)
			(layer "F.Fab")
		)
		(fp_line
			(start -0.12065 -0.2794)
			(end 0.12065 -0.2794)
			(stroke
				(width 0.1)
				(type default)
			)
			(layer "F.Fab")
		)
		(fp_line
			(start -0.12065 -0.305054)
			(end -0.12065 -0.2794)
			(stroke
				(width 0.1)
				(type default)
			)
			(layer "F.Fab")
		)
		(fp_line
			(start -0.67945 0.3048)
			(end -0.67945 -0.305054)
			(stroke
				(width 0.1)
				(type default)
			)
			(layer "F.Fab")
		)
		(fp_line
			(start -0.67945 -0.305054)
			(end -0.12065 -0.305054)
			(stroke
				(width 0.1)
				(type default)
			)
			(layer "F.Fab")
		)
		(pad "1" smd circle
			(at -0.40005 0 180)
			(size 0 0)
			(layers "F.Cu" "F.Mask" "F.Paste")
			(net "SMB_PCIE0_3V3AUX_SDA_R3")
		)
		(pad "2" smd circle
			(at 0.40005 0 180)
			(size 0 0)
			(layers "F.Cu" "F.Mask" "F.Paste")
			(net "SMB_SENSOR_M2_P0_3V3AUX_SDA")
		)
	)
	(footprint ""
		(layer "F.Cu")
		(at 300.754034 -15.572994)
		(property "Reference" "R4197"
			(at 0 0 0)
			(layer "F.SilkS")
			(hide yes)
			(effects
				(font
					(size 1.27 1.27)
				)
			)
		)
		(property "Value" ""
			(at 0 0 0)
			(layer "F.Fab")
			(effects
				(font
					(size 1.27 1.27)
				)
			)
		)
		(duplicate_pad_numbers_are_jumpers no)
		(fp_line
			(start -0.7874 -0.4064)
			(end 0.7874 -0.4064)
			(stroke
				(width 0.1524)
				(type default)
			)
			(layer "F.SilkS")
		)
		(fp_line
			(start -0.7874 0.4064)
			(end -0.7874 -0.4064)
			(stroke
				(width 0.1524)
				(type default)
			)
			(layer "F.SilkS")
		)
		(fp_line
			(start 0.7874 -0.4064)
			(end 0.7874 0.4064)
			(stroke
				(width 0.1524)
				(type default)
			)
			(layer "F.SilkS")
		)
		(fp_line
			(start 0.7874 0.4064)
			(end -0.7874 0.4064)
			(stroke
				(width 0.1524)
				(type default)
			)
			(layer "F.SilkS")
		)
		(fp_line
			(start -0.67945 -0.305054)
			(end -0.12065 -0.305054)
			(stroke
				(width 0.1)
				(type default)
			)
			(layer "F.Fab")
		)
		(fp_line
			(start -0.67945 0.3048)
			(end -0.67945 -0.305054)
			(stroke
				(width 0.1)
				(type default)
			)
			(layer "F.Fab")
		)
		(fp_line
			(start -0.12065 -0.305054)
			(end -0.12065 -0.2794)
			(stroke
				(width 0.1)
				(type default)
			)
			(layer "F.Fab")
		)
		(fp_line
			(start -0.12065 -0.2794)
			(end 0.12065 -0.2794)
			(stroke
				(width 0.1)
				(type default)
			)
			(layer "F.Fab")
		)
		(fp_line
			(start -0.12065 0.2794)
			(end -0.12065 0.3048)
			(stroke
				(width 0.1)
				(type default)
			)
			(layer "F.Fab")
		)
		(fp_line
			(start -0.12065 0.3048)
			(end -0.67945 0.3048)
			(stroke
				(width 0.1)
				(type default)
			)
			(layer "F.Fab")
		)
		(fp_line
			(start 0.120396 0.2794)
			(end -0.12065 0.2794)
			(stroke
				(width 0.1)
				(type default)
			)
			(layer "F.Fab")
		)
		(fp_line
			(start 0.120396 0.3048)
			(end 0.120396 0.2794)
			(stroke
				(width 0.1)
				(type default)
			)
			(layer "F.Fab")
		)
		(fp_line
			(start 0.12065 -0.3048)
			(end 0.67945 -0.3048)
			(stroke
				(width 0.1)
				(type default)
			)
			(layer "F.Fab")
		)
		(fp_line
			(start 0.12065 -0.2794)
			(end 0.12065 -0.3048)
			(stroke
				(width 0.1)
				(type default)
			)
			(layer "F.Fab")
		)
		(fp_line
			(start 0.67945 -0.3048)
			(end 0.67945 0.3048)
			(stroke
				(width 0.1)
				(type default)
			)
			(layer "F.Fab")
		)
		(fp_line
			(start 0.67945 0.3048)
			(end 0.120396 0.3048)
			(stroke
				(width 0.1)
				(type default)
			)
			(layer "F.Fab")
		)
		(pad "1" smd circle
			(at -0.40005 0)
			(size 0 0)
			(layers "F.Cu" "F.Mask" "F.Paste")
			(net "U271_1_ADD1")
		)
		(pad "2" smd circle
			(at 0.40005 0)
			(size 0 0)
			(layers "F.Cu" "F.Mask" "F.Paste")
			(net "GND")
		)
	)
)
